# BASEBOARD_FAB2 (Tioga Pass) — schematic netlist excerpt (pin names and nets, part order shuffled) for the footprints in the layout excerpt that follows; sources: Cadence DE-HDL packaged netlist, KiCad conversion of Wiwynn_Tioga_Pass_MB.brd

R3P36  RES  1.00K 1% CHIP  pkg 0402  page 96 : A = P3V3_STBY ; B = PU_GTL2014_1_DIR
C3P23  CAP  0.22UF 16V 10% X7R  pkg 0402  page 107 : A = P3E_CPU0_PE1_SS_TXP<3> ; B = P3E_CPU0_PE1_PCH_TXP<3>

(kicad_pcb
	(version 20260206)
	(generator "pcbnew")
	(generator_version "10.0")
	(general
		(thickness 1.6)
		(legacy_teardrops no)
	)
	(paper "A4")
	(title_block
		(title "Wiwynn_Tioga_Pass_MB.brd")
		(comment 1 "Tioga Pass / footprints 3317-3318 of 4770")
	)
	(layers
		(0 "F.Cu" signal "TOP")
		(4 "In1.Cu" signal "L2GND")
		(6 "In2.Cu" signal "L3")
		(8 "In3.Cu" signal "L4GND")
		(10 "In4.Cu" signal "L5")
		(12 "In5.Cu" signal "L6GND")
		(14 "In6.Cu" signal "L7VCC")
		(16 "In7.Cu" signal "L8VCC")
		(18 "In8.Cu" signal "L9GND")
		(20 "In9.Cu" signal "L10")
		(22 "In10.Cu" signal "L11GND")
		(24 "In11.Cu" signal "L12")
		(26 "In12.Cu" signal "L13GND")
		(2 "B.Cu" signal "BOTTOM")
		(9 "F.Adhes" user "F.Adhesive")
		(11 "B.Adhes" user "B.Adhesive")
		(13 "F.Paste" user "Package Geometry/Pastemask Top")
		(15 "B.Paste" user "Package Geometry/Pastemask Bottom")
		(5 "F.SilkS" user "Ref Des/Silkscreen Top")
		(7 "B.SilkS" user "Ref Des/Silkscreen Bottom")
		(1 "F.Mask" user "Board Geometry/Soldermask Top")
		(3 "B.Mask" user "Board Geometry/Soldermask Bottom")
		(17 "Dwgs.User" user "User.Drawings")
		(19 "Cmts.User" user "User.Comments")
		(21 "Eco1.User" user "User.Eco1")
		(23 "Eco2.User" user "User.Eco2")
		(25 "Edge.Cuts" user "Board Geometry/Outline")
		(27 "Margin" user)
		(31 "F.CrtYd" user "Package Geometry/Place Bound Top")
		(29 "B.CrtYd" user "Package Geometry/Place Bound Bottom")
		(35 "F.Fab" user "Ref Des/Assembly Top")
		(33 "B.Fab" user "Ref Des/Assembly Bottom")
	)
	(footprint ""
		(layer "B.Cu")
		(at 347.17736 -77.788516 180)
		(property "Reference" "C3P23"
			(at 0 0 0)
			(layer "B.SilkS")
			(hide yes)
			(effects
				(font
					(size 1.27 1.27)
				)
				(justify mirror)
			)
		)
		(property "Value" ""
			(at 0 0 0)
			(layer "B.Fab")
			(effects
				(font
					(size 1.27 1.27)
				)
				(justify mirror)
			)
		)
		(duplicate_pad_numbers_are_jumpers no)
		(fp_poly
			(pts
				(xy -0.3048 -0.1016) (xy -0.3048 0.9906) (xy 0.3048 0.9906) (xy 0.3048 -0.1016)
			)
			(stroke
				(width 0)
				(type default)
			)
			(fill no)
			(layer "B.CrtYd")
		)
		(fp_line
			(start 0.3048 0.9906)
			(end -0.3048 0.9906)
			(stroke
				(width 0.1)
				(type default)
			)
			(layer "B.Fab")
		)
		(fp_line
			(start 0.3048 -0.1016)
			(end 0.3048 0.9906)
			(stroke
				(width 0.1)
				(type default)
			)
			(layer "B.Fab")
		)
		(fp_line
			(start -0.3048 0.9906)
			(end -0.3048 -0.1016)
			(stroke
				(width 0.1)
				(type default)
			)
			(layer "B.Fab")
		)
		(fp_line
			(start -0.3048 -0.1016)
			(end 0.3048 -0.1016)
			(stroke
				(width 0.1)
				(type default)
			)
			(layer "B.Fab")
		)
		(pad "1" smd rect
			(at 0 0)
			(size 0.508 0.508)
			(layers "B.Cu" "B.Mask" "B.Paste")
			(net "P3E_CPU0_PE1_SS_TXP<3>")
		)
		(pad "2" smd rect
			(at 0 0.889)
			(size 0.508 0.508)
			(layers "B.Cu" "B.Mask" "B.Paste")
			(net "P3E_CPU0_PE1_PCH_TXP<3>")
		)
		(zone
			(layer "B.Cu")
			(hatch none 0.5)
			(connect_pads
				(clearance 0)
			)
			(min_thickness 0.25)
			(keepout
				(tracks not_allowed)
				(vias allowed)
				(pads allowed)
				(copperpour not_allowed)
				(footprints allowed)
			)
			(placement
				(enabled no)
				(sheetname "")
			)
			(fill
				(thermal_gap 0.5)
				(thermal_bridge_width 0.5)
				(island_removal_mode 0)
			)
			(polygon
				(pts
					(xy 346.92336 -78.423516) (xy 347.43136 -78.423516) (xy 347.43136 -78.042516) (xy 346.92336 -78.042516)
				)
			)
		)
		(zone
			(layer "B.Cu")
			(hatch none 0.5)
			(connect_pads
				(clearance 0)
			)
			(min_thickness 0.25)
			(keepout
				(tracks allowed)
				(vias not_allowed)
				(pads allowed)
				(copperpour not_allowed)
				(footprints allowed)
			)
			(placement
				(enabled no)
				(sheetname "")
			)
			(fill
				(thermal_gap 0.5)
				(thermal_bridge_width 0.5)
				(island_removal_mode 0)
			)
			(polygon
				(pts
					(xy 346.92336 -78.042516) (xy 347.43136 -78.042516) (xy 347.43136 -78.423516) (xy 346.92336 -78.423516)
				)
			)
		)
	)
	(footprint ""
		(layer "B.Cu")
		(at 374.1928 -53.8099 -90)
		(property "Reference" "R3P36"
			(at 0 0 90)
			(layer "B.SilkS")
			(hide yes)
			(effects
				(font
					(size 1.27 1.27)
				)
				(justify mirror)
			)
		)
		(property "Value" ""
			(at 0 0 90)
			(layer "B.Fab")
			(effects
				(font
					(size 1.27 1.27)
				)
				(justify mirror)
			)
		)
		(duplicate_pad_numbers_are_jumpers no)
		(fp_poly
			(pts
				(xy 0.2794 -0.1016) (xy -0.2794 -0.1016) (xy -0.2794 0.9906) (xy 0.2794 0.9906)
			)
			(stroke
				(width 0)
				(type default)
			)
			(fill no)
			(layer "B.CrtYd")
		)
		(fp_line
			(start -0.2794 0.9906)
			(end -0.2794 -0.1016)
			(stroke
				(width 0.1)
				(type default)
			)
			(layer "B.Fab")
		)
		(fp_line
			(start 0.2794 0.9906)
			(end -0.2794 0.9906)
			(stroke
				(width 0.1)
				(type default)
			)
			(layer "B.Fab")
		)
		(fp_line
			(start -0.2794 -0.1016)
			(end 0.2794 -0.1016)
			(stroke
				(width 0.1)
				(type default)
			)
			(layer "B.Fab")
		)
		(fp_line
			(start 0.2794 -0.1016)
			(end 0.2794 0.9906)
			(stroke
				(width 0.1)
				(type default)
			)
			(layer "B.Fab")
		)
		(pad "1" smd rect
			(at 0 0 90)
			(size 0.508 0.508)
			(layers "B.Cu" "B.Mask" "B.Paste")
			(net "P3V3_STBY")
		)
		(pad "2" smd rect
			(at 0 0.889 90)
			(size 0.508 0.508)
			(layers "B.Cu" "B.Mask" "B.Paste")
			(net "PU_GTL2014_1_DIR")
		)
		(zone
			(layer "B.Cu")
			(hatch none 0.5)
			(connect_pads
				(clearance 0)
			)
			(min_thickness 0.25)
			(keepout
				(tracks not_allowed)
				(vias allowed)
				(pads allowed)
				(copperpour not_allowed)
				(footprints allowed)
			)
			(placement
				(enabled no)
				(sheetname "")
			)
			(fill
				(thermal_gap 0.5)
				(thermal_bridge_width 0.5)
				(island_removal_mode 0)
			)
			(polygon
				(pts
					(xy 373.5578 -53.5559) (xy 373.5578 -54.0639) (xy 373.9388 -54.0639) (xy 373.9388 -53.5559)
				)
			)
		)
		(zone
			(layer "B.Cu")
			(hatch none 0.5)
			(connect_pads
				(clearance 0)
			)
			(min_thickness 0.25)
			(keepout
				(tracks allowed)
				(vias not_allowed)
				(pads allowed)
				(copperpour not_allowed)
				(footprints allowed)
			)
			(placement
				(enabled no)
				(sheetname "")
			)
			(fill
				(thermal_gap 0.5)
				(thermal_bridge_width 0.5)
				(island_removal_mode 0)
			)
			(polygon
				(pts
					(xy 373.9388 -53.5559) (xy 373.9388 -54.0639) (xy 373.5578 -54.0639) (xy 373.5578 -53.5559)
				)
			)
		)
	)
)
